FILE_TYPE = CONNECTIVITY;
{Allegro Design Entry HDL 16.6-p007 (v16-6-112F) 10/10/2012}
"PAGE_NUMBER" = 220;
0"NC";
1"PVDDQ_DEF\g";
2"GND\g";
3"VR_FET_SW_P12V_STBY_PVDDQ_DEF\g";
4"P12V_STBY\g";
5"GND\g";
6"PVDDQ_DEF\g";
7"PVDDQ_DEF\g";
8"GND\g";
9"PVDDQ_DEF\g";
10"GND\g";
11"PVDDQ_DEF\g";
12"GND\g";
13"PVDDQ_DEF\g";
14"GND\g";
15"GND\g";
16"PVDDQ_DEF\g";
17"GND\g";
18"PVDDQ_DEF\g";
19"GND\g";
20"PVDDQ_DEF\g";
21"GND\g";
22"GND\g";
23"PVDDQ_DEF\g";
24"PVDDQ_DEF\g";
25"GND\g";
26"PVDDQ_DEF\g";
27"GND\g";
28"VSENSE_PVDDQ_DEF_P";
29"VSENSE_PVDDQ_DEF_N";
%"PVDDQ_DEF"
"1","(2675,1950)","0","mstr_symbols","I109";
;
ROOM"VDDQ_DEF_PWR_VR"
BOM_COST"MEM_VRD_PVDDQ_DEF"
CDS_LIB"mstr_symbols"
VOLTAGE"1.2V"
BODY_TYPE"PLUMBING"
HDL_POWER"PVDDQ_DEF";
"G\NAC"1;
%"GND"
"1","(4400,1300)","0","mstr_symbols","I114";
;
VOLTAGE"0"
CDS_LIB"mstr_symbols"
SIZE"1B"
ROOM"VDDQ_DEF_PWR_VR"
BOM_COST"MEM_VRD_PVDDQ_DEF"
BODY_TYPE"PLUMBING"
HDL_POWER"GND";
"A\NAC"2;
%"VCC_CORE"
"1","(1900,1500)","0","mstr_symbols","I120";
;
HDL_POWER"VR_FET_SW_P12V_STBY_PVDDQ_DEF"
CDS_LIB"mstr_symbols";
"A"3;
%"P12V_STBY"
"1","(-2250,1425)","0","mstr_symbols","I176";
;
HDL_POWER"P12V_STBY"
BODY_TYPE"PLUMBING"
CDS_LIB"mstr_symbols"
SIZE"1B"
VOLTAGE"12.0V";
"G\NAC"4;
%"GND"
"1","(-400,2625)","0","mstr_symbols","I181";
;
HDL_POWER"GND"
BODY_TYPE"PLUMBING"
ROOM"VDDQ_ABC_PWR_VR"
BOM_COST"MEM_VRD_PVDDQ_CD"
SIZE"1B"
CDS_LIB"mstr_symbols"
VOLTAGE"0";
"A\NAC"5;
%"PVDDQ_DEF"
"1","(-2300,3250)","0","mstr_symbols","I185";
;
HDL_POWER"PVDDQ_DEF"
BODY_TYPE"PLUMBING"
VOLTAGE"1.2V"
CDS_LIB"mstr_symbols"
BOM_COST"MEM_VRD_PVPP_DEF"
ROOM"VDDQ_DEF_PWR_VR";
"G\NAC"6;
%"PVDDQ_DEF"
"1","(2650,1225)","0","mstr_symbols","I189";
;
ROOM"VDDQ_DEF_PWR_VR"
BOM_COST"MEM_VRD_PVDDQ_DEF"
VOLTAGE"1.2V"
CDS_LIB"mstr_symbols"
BODY_TYPE"PLUMBING"
HDL_POWER"PVDDQ_DEF";
"G\NAC"7;
%"GND"
"1","(3600,600)","0","mstr_symbols","I191";
;
CDS_LIB"mstr_symbols"
SIZE"1B"
VOLTAGE"0"
BOM_COST"MEM_VRD_PVDDQ_DEF"
ROOM"VDDQ_DEF_PWR_VR"
BODY_TYPE"PLUMBING"
HDL_POWER"GND";
"A\NAC"8;
%"CAP_A"
"1","(2650,950)","0","dev_discrete","I192";
;
VALUE"47UF"
PART_NUMBER"602433-106"
PACK_TYPE"0603V"
GROUP"PWR_MLCC_CAP"
TOLERANCE"20%"
VOLTAGE"4V"
MATERIAL"X5R"
LOCATION"C5L15"
BOM_SS"NOPOP"
CDS_LOCATION"C5L15"
CDS_SEC"1"
SEC_TYPE"0603V"
SEC"1"
CDS_LIB"dev_discrete";
"B"
$PN"2"8;
"A"
$PN"1"7;
%"CAP_A"
"1","(3000,950)","0","dev_discrete","I193";
;
VALUE"47UF"
MATERIAL"X5R"
GROUP"PWR_MLCC_CAP"
PART_NUMBER"602433-106"
PACK_TYPE"0603V"
TOLERANCE"20%"
BOM_SS"NOPOP"
VOLTAGE"4V"
LOCATION"C5A5"
CDS_LOCATION"C5A5"
CDS_SEC"1"
SEC_TYPE"0603V"
SEC"1"
CDS_LIB"dev_discrete";
"B"
$PN"2"8;
"A"
$PN"1"7;
%"CAP_A"
"1","(3400,950)","0","dev_discrete","I194";
;
LOCATION"C5B1"
VALUE"47UF"
VOLTAGE"4V"
BOM_SS"NOPOP"
TOLERANCE"20%"
MATERIAL"X5R"
PART_NUMBER"602433-106"
PACK_TYPE"0603V"
GROUP"PWR_MLCC_CAP"
CDS_LOCATION"C5B1"
CDS_SEC"1"
SEC_TYPE"0603V"
SEC"1"
CDS_LIB"dev_discrete";
"B"
$PN"2"8;
"A"
$PN"1"7;
%"CAP_A"
"1","(4125,1675)","0","dev_discrete","I195";
;
LOCATION"C5M9"
MATERIAL"X5R"
PACK_TYPE"0603V"
TOLERANCE"20%"
VOLTAGE"4V"
VALUE"47UF"
PART_NUMBER"602433-106"
BOM_SS"NOPOP"
GROUP"PWR_MLCC_CAP"
SEC"1"
SEC_TYPE"0603V"
CDS_SEC"1"
CDS_LOCATION"C5M9"
CDS_LIB"dev_discrete";
"B"
$PN"2"2;
"A"
$PN"1"1;
%"CAP_A"
"1","(3775,1675)","0","dev_discrete","I196";
;
BOM_SS"078.1061T.M001"
TOLERANCE"20%"
VOLTAGE"4V"
MATERIAL"X5R"
LOCATION"C4M5"
VALUE"47UF"
PART_NUMBER"602433-106"
PACK_TYPE"0603V"
GROUP"PWR_MLCC_CAP"
SEC"1"
SEC_TYPE"0603V"
CDS_SEC"1"
CDS_LOCATION"C4M5"
CDS_LIB"dev_discrete";
"B"
$PN"2"2;
"A"
$PN"1"1;
%"CAP_A"
"1","(2675,1675)","0","dev_discrete","I197";
;
BOM_SS"NOPOP"
VOLTAGE"4V"
TOLERANCE"20%"
PACK_TYPE"0603V"
PART_NUMBER"602433-106"
MATERIAL"X5R"
LOCATION"C5B2"
VALUE"47UF"
GROUP"PWR_MLCC_CAP"
SEC"1"
SEC_TYPE"0603V"
CDS_SEC"1"
CDS_LOCATION"C5B2"
CDS_LIB"dev_discrete";
"B"
$PN"2"2;
"A"
$PN"1"1;
%"CAP_A"
"1","(3025,1675)","0","dev_discrete","I198";
;
MATERIAL"X5R"
VOLTAGE"4V"
TOLERANCE"20%"
PART_NUMBER"602433-106"
PACK_TYPE"0603V"
GROUP"PWR_MLCC_CAP"
BOM_SS"NOPOP"
VALUE"47UF"
LOCATION"C5M10"
CDS_LOCATION"C5M10"
CDS_SEC"1"
SEC_TYPE"0603V"
SEC"1"
CDS_LIB"dev_discrete";
"B"
$PN"2"2;
"A"
$PN"1"1;
%"CAP_A"
"1","(3425,1675)","0","dev_discrete","I199";
;
VALUE"47UF"
LOCATION"C5M3"
VOLTAGE"4V"
TOLERANCE"20%"
PACK_TYPE"0603V"
PART_NUMBER"602433-106"
MATERIAL"X5R"
GROUP"PWR_MLCC_CAP"
BOM_SS"NOPOP"
CDS_SEC"1"
SEC_TYPE"0603V"
SEC"1"
CDS_LOCATION"C5M3"
CDS_LIB"dev_discrete";
"B"
$PN"2"2;
"A"
$PN"1"1;
%"CAP_A"
"1","(4525,1675)","0","dev_discrete","I200";
;
PACK_TYPE"0603V"
LOCATION"C5M11"
VALUE"47UF"
TOLERANCE"20%"
MATERIAL"X5R"
PART_NUMBER"602433-106"
VOLTAGE"4V"
BOM_SS"NOPOP"
GROUP"PWR_MLCC_CAP"
SEC"1"
CDS_SEC"1"
SEC_TYPE"0603V"
CDS_LOCATION"C5M11"
CDS_LIB"dev_discrete";
"B"
$PN"2"2;
"A"
$PN"1"1;
%"PVDDQ_DEF"
"1","(-1450,3250)","0","mstr_symbols","I201";
;
HDL_POWER"PVDDQ_DEF"
BODY_TYPE"PLUMBING"
VOLTAGE"1.2V"
CDS_LIB"mstr_symbols"
BOM_COST"MEM_VRD_PVPP_DEF"
ROOM"VDDQ_DEF_PWR_VR";
"G\NAC"9;
%"GND"
"1","(-1950,2475)","0","mstr_symbols","I202";
;
VOLTAGE"0"
CDS_LIB"mstr_symbols"
SIZE"1B"
BOM_COST"MEM_VRD_PVDDQ_CD"
ROOM"VDDQ_ABC_PWR_VR"
BODY_TYPE"PLUMBING"
HDL_POWER"GND";
"A\NAC"10;
%"PVDDQ_DEF"
"1","(-2150,350)","0","mstr_symbols","I218";
;
VOLTAGE"1.2V"
CDS_LIB"mstr_symbols"
BODY_TYPE"PLUMBING"
HDL_POWER"PVDDQ_DEF";
"G\NAC"11;
%"GND"
"1","(-2150,-225)","0","mstr_symbols","I220";
;
ROOM"VDDQ_ABC_PWR_VR"
BOM_COST"PROC_VRD_VCCIN_CPU0"
CDS_LIB"mstr_symbols"
SIZE"1B"
VOLTAGE"0"
BODY_TYPE"PLUMBING"
HDL_POWER"GND";
"A\NAC"12;
%"PVDDQ_DEF"
"1","(-2150,-400)","0","mstr_symbols","I235";
;
ROOM"VDDQ_DEF_PWR_VR"
BOM_COST"PROC_SOCKET "
CDS_LIB"mstr_symbols"
VOLTAGE"1.2V"
BODY_TYPE"PLUMBING"
HDL_POWER"PVDDQ_DEF";
"G\NAC"13;
%"GND"
"1","(-2150,-1000)","0","mstr_symbols","I238";
;
ROOM"VDDQ_ABC_PWR_VR"
BOM_COST"PROC_VRD_VCCIN_CPU0"
SIZE"1B"
CDS_LIB"mstr_symbols"
VOLTAGE"0"
BODY_TYPE"PLUMBING"
HDL_POWER"GND";
"A\NAC"14;
%"SHUNT"
"1","(-300,2075)","0","mstr_misc","I239";
;
CDS_SEC"1"
CDS_LOCATION"SH4L2"
LOCATION"SH4L2"
PART_NUMBER"N_A"
SEC_TYPE"SH0201"
SEC"1"
CDS_LIB"mstr_misc"
MATERIAL"EMPTY"
PACK_TYPE"SH0201"
PIN_SHORT"A:B";
"A"
$PN"1"28;
"B"
$PN"2"23;
%"SHUNT"
"1","(-325,1625)","0","mstr_misc","I240";
;
CDS_SEC"1"
CDS_LOCATION"SH4L1"
LOCATION"SH4L1"
PART_NUMBER"N_A"
SEC_TYPE"SH0201"
CDS_LIB"mstr_misc"
SEC"1"
MATERIAL"EMPTY"
PACK_TYPE"SH0201"
PIN_SHORT"A:B";
"A"
$PN"1"29;
"B"
$PN"2"22;
%"IND-100NH-35-GP"
"1","(-1950,1325)","1","w_hdl","I241";
;
CDS_SEC"1"
CDS_LOCATION"L7A5"
RATED"ISAT=16A@25C"
TYPE"IRMS=29A@DELTA_T<45C"
PACK_SIZE"DCR=0.16MOHM"
ATTRIBUTE"100NH"
VALUE"IND-100NH-35-GP"
LOCATION"L7A5"
CDS_LMAN_SYM_OUTLINE"-75,100,75,-100"
CDS_LIB"w_hdl"
PART_NUMBER"068.1011N.M001"
SEC_TYPE"DISCRET-G8"
SEC"1"
PACK_TYPE"DISCRET-G8";
"F"
$PN"2"3;
"S"
$PN"1"4;
%"GND"
"1","(175,2525)","0","mstr_symbols","I245";
;
HDL_POWER"GND"
BODY_TYPE"PLUMBING"
VOLTAGE"0"
SIZE"1B"
CDS_LIB"mstr_symbols";
"A\NAC"15;
%"PVDDQ_DEF"
"1","(175,3200)","0","mstr_symbols","I248";
;
HDL_POWER"PVDDQ_DEF"
BODY_TYPE"PLUMBING"
VOLTAGE"1.2V"
BOM_COST"MEM_VRD_PVPP_DEF"
ROOM"VDDQ_DEF_PWR_VR"
CDS_LIB"mstr_symbols";
"G\NAC"16;
%"CAP_A"
"1","(1550,2050)","0","dev_discrete","I249";
;
LOCATION"C5D4"
GROUP"PWR_MLCC_CAP"
PART_NUMBER"E15431-004"
PACK_TYPE"0603V"
MATERIAL"X6S"
TOLERANCE"20%"
VOLTAGE"4V"
VALUE"22.0UF"
ROOM"PVCCIN_CPU0_DECAP_VR"
$SEC"1"
CDS_SEC"1"
CDS_LIB"dev_discrete"
BOM_COST"PROC_SOCKET"
CDS_LOCATION"C5D4";
"B"
$PN"2"17;
"A"
$PN"1"18;
%"CAP_A"
"1","(1200,2050)","0","dev_discrete","I250";
;
LOCATION"C5D3"
VOLTAGE"4V"
GROUP"PWR_MLCC_CAP"
VALUE"22.0UF"
TOLERANCE"20%"
MATERIAL"X6S"
PART_NUMBER"E15431-004"
PACK_TYPE"0603V"
CDS_LOCATION"C5D3"
BOM_COST"PROC_SOCKET"
CDS_LIB"dev_discrete"
CDS_SEC"1"
$SEC"1"
ROOM"PVCCIN_CPU0_DECAP_VR";
"B"
$PN"2"17;
"A"
$PN"1"18;
%"CAP_A"
"1","(850,2050)","0","dev_discrete","I251";
;
GROUP"PWR_MLCC_CAP"
LOCATION"C5D2"
VALUE"22.0UF"
PACK_TYPE"0603V"
MATERIAL"X6S"
TOLERANCE"20%"
VOLTAGE"4V"
PART_NUMBER"E15431-004"
CDS_LOCATION"C5D2"
BOM_COST"PROC_SOCKET"
CDS_LIB"dev_discrete"
CDS_SEC"1"
$SEC"1"
ROOM"PVCCIN_CPU0_DECAP_VR";
"B"
$PN"2"17;
"A"
$PN"1"18;
%"CAP_A"
"1","(500,2050)","0","dev_discrete","I252";
;
VALUE"22.0UF"
GROUP"PWR_MLCC_CAP"
VOLTAGE"4V"
TOLERANCE"20%"
MATERIAL"X6S"
PART_NUMBER"E15431-004"
LOCATION"C5D1"
PACK_TYPE"0603V"
CDS_LOCATION"C5D1"
BOM_COST"PROC_SOCKET"
CDS_LIB"dev_discrete"
CDS_SEC"1"
$SEC"1"
ROOM"PVCCIN_CPU0_DECAP_VR";
"B"
$PN"2"17;
"A"
$PN"1"18;
%"GND"
"1","(1550,1700)","0","mstr_symbols","I253";
;
VOLTAGE"0"
SIZE"1B"
CDS_LIB"mstr_symbols"
BODY_TYPE"PLUMBING"
HDL_POWER"GND";
"A\NAC"17;
%"PVDDQ_DEF"
"1","(500,2300)","0","mstr_symbols","I254";
;
VOLTAGE"1.2V"
BOM_COST"MEM_VRD_PVPP_DEF"
ROOM"VDDQ_DEF_PWR_VR"
CDS_LIB"mstr_symbols"
BODY_TYPE"PLUMBING"
HDL_POWER"PVDDQ_DEF";
"G\NAC"18;
%"GND"
"1","(1600,2750)","0","mstr_symbols","I255";
;
VOLTAGE"0"
SIZE"1B"
CDS_LIB"mstr_symbols"
BODY_TYPE"PLUMBING"
HDL_POWER"GND";
"A\NAC"19;
%"PVDDQ_DEF"
"1","(1600,3150)","0","mstr_symbols","I257";
;
HDL_POWER"PVDDQ_DEF"
BODY_TYPE"PLUMBING"
VOLTAGE"1.2V"
BOM_COST"MEM_VRD_PVPP_DEF"
ROOM"VDDQ_DEF_PWR_VR"
CDS_LIB"mstr_symbols";
"G\NAC"20;
%"CAP_A"
"1","(-1450,2975)","0","dev_discrete","I258";
;
VALUE"22.0UF"
PART_NUMBER"E15431-004"
PACK_TYPE"0603V"
GROUP"PWR_MLCC_CAP"
LOCATION"C5D9"
VOLTAGE"4V"
MATERIAL"X6S"
TOLERANCE"20%"
BOM_COST"PROC_SOCKET"
CDS_LIB"dev_discrete"
CDS_SEC"1"
$SEC"1"
ROOM"PVCCIN_CPU0_DECAP_VR"
CDS_LOCATION"C5D9";
"B"
$PN"2"5;
"A"
$PN"1"9;
%"CAP_A"
"1","(-1100,2975)","0","dev_discrete","I259";
;
PART_NUMBER"E15431-004"
PACK_TYPE"0603V"
GROUP"PWR_MLCC_CAP"
MATERIAL"X6S"
VOLTAGE"4V"
VALUE"22.0UF"
LOCATION"C5D6"
TOLERANCE"20%"
BOM_COST"PROC_SOCKET"
CDS_LIB"dev_discrete"
CDS_SEC"1"
$SEC"1"
ROOM"PVCCIN_CPU0_DECAP_VR"
CDS_LOCATION"C5D6";
"B"
$PN"2"5;
"A"
$PN"1"9;
%"CAP_A"
"1","(-750,2975)","0","dev_discrete","I260";
;
TOLERANCE"20%"
MATERIAL"X6S"
PART_NUMBER"E15431-004"
GROUP"PWR_MLCC_CAP"
PACK_TYPE"0603V"
LOCATION"C5D7"
VOLTAGE"4V"
VALUE"22.0UF"
BOM_COST"PROC_SOCKET"
CDS_LIB"dev_discrete"
CDS_SEC"1"
$SEC"1"
ROOM"PVCCIN_CPU0_DECAP_VR"
CDS_LOCATION"C5D7";
"B"
$PN"2"5;
"A"
$PN"1"9;
%"CAP_A"
"1","(-400,2975)","0","dev_discrete","I261";
;
LOCATION"C5D8"
VALUE"22.0UF"
PART_NUMBER"E15431-004"
GROUP"PWR_MLCC_CAP"
PACK_TYPE"0603V"
MATERIAL"X6S"
TOLERANCE"20%"
VOLTAGE"4V"
BOM_COST"PROC_SOCKET"
CDS_LIB"dev_discrete"
CDS_SEC"1"
$SEC"1"
ROOM"PVCCIN_CPU0_DECAP_VR"
CDS_LOCATION"C5D8";
"B"
$PN"2"5;
"A"
$PN"1"9;
%"CAP_A"
"1","(-2150,100)","0","dev_discrete","I262";
;
MATERIAL"X5R"
TOLERANCE"20%"
VOLTAGE"4V"
VALUE"47UF"
PACK_TYPE"0603V"
PART_NUMBER"602433-106"
LOCATION"C5A1"
GROUP"PWR_MLCC_CAP"
BOM_SS"E15431-004"
CDS_LIB"dev_discrete"
SEC"1"
SEC_TYPE"0603V"
CDS_SEC"1"
CDS_LOCATION"C5A1";
"B"
$PN"2"12;
"A"
$PN"1"11;
%"CAP_A"
"1","(-1850,100)","0","dev_discrete","I263";
;
LOCATION"C5A15"
TOLERANCE"20%"
VOLTAGE"4V"
VALUE"47UF"
GROUP"PWR_MLCC_CAP"
PACK_TYPE"0603V"
PART_NUMBER"602433-106"
MATERIAL"X5R"
BOM_SS"E15431-004"
CDS_SEC"1"
SEC_TYPE"0603V"
SEC"1"
CDS_LIB"dev_discrete"
CDS_LOCATION"C5A15";
"B"
$PN"2"12;
"A"
$PN"1"11;
%"CAP_A"
"1","(-1550,100)","0","dev_discrete","I264";
;
MATERIAL"X5R"
PART_NUMBER"602433-106"
PACK_TYPE"0603V"
LOCATION"C5A12"
VOLTAGE"4V"
TOLERANCE"20%"
VALUE"47UF"
GROUP"PWR_MLCC_CAP"
BOM_SS"E15431-004"
CDS_LIB"dev_discrete"
SEC"1"
SEC_TYPE"0603V"
CDS_SEC"1"
CDS_LOCATION"C5A12";
"B"
$PN"2"12;
"A"
$PN"1"11;
%"CAP_A"
"1","(-1275,100)","0","dev_discrete","I265";
;
VALUE"47UF"
VOLTAGE"4V"
MATERIAL"X5R"
TOLERANCE"20%"
LOCATION"C5A13"
GROUP"PWR_MLCC_CAP"
PART_NUMBER"602433-106"
PACK_TYPE"0603V"
BOM_SS"E15431-004"
CDS_SEC"1"
SEC_TYPE"0603V"
SEC"1"
CDS_LIB"dev_discrete"
CDS_LOCATION"C5A13";
"B"
$PN"2"12;
"A"
$PN"1"11;
%"CAP_A"
"1","(-1000,100)","0","dev_discrete","I266";
;
LOCATION"C5A2"
VOLTAGE"4V"
TOLERANCE"20%"
PACK_TYPE"0603V"
PART_NUMBER"602433-106"
MATERIAL"X5R"
VALUE"47UF"
GROUP"PWR_MLCC_CAP"
BOM_SS"E15431-004"
CDS_SEC"1"
SEC_TYPE"0603V"
SEC"1"
CDS_LIB"dev_discrete"
CDS_LOCATION"C5A2";
"B"
$PN"2"12;
"A"
$PN"1"11;
%"CAP_A"
"1","(-700,100)","0","dev_discrete","I267";
;
VALUE"47UF"
PART_NUMBER"602433-106"
TOLERANCE"20%"
VOLTAGE"4V"
LOCATION"C5A14"
MATERIAL"X5R"
PACK_TYPE"0603V"
GROUP"PWR_MLCC_CAP"
BOM_SS"E15431-004"
CDS_LIB"dev_discrete"
SEC"1"
SEC_TYPE"0603V"
CDS_SEC"1"
CDS_LOCATION"C5A14";
"B"
$PN"2"12;
"A"
$PN"1"11;
%"CAP_A"
"1","(-400,100)","0","dev_discrete","I268";
;
MATERIAL"X5R"
LOCATION"C5A6"
TOLERANCE"20%"
VALUE"47UF"
VOLTAGE"4V"
PACK_TYPE"0603V"
PART_NUMBER"602433-106"
GROUP"PWR_MLCC_CAP"
BOM_SS"E15431-004"
SEC"1"
SEC_TYPE"0603V"
CDS_LOCATION"C5A6"
CDS_LIB"dev_discrete"
CDS_SEC"1";
"B"
$PN"2"12;
"A"
$PN"1"11;
%"CAP_A"
"1","(-125,100)","0","dev_discrete","I269";
;
PART_NUMBER"602433-106"
PACK_TYPE"0603V"
MATERIAL"X5R"
TOLERANCE"20%"
VOLTAGE"4V"
VALUE"47UF"
LOCATION"C5A7"
GROUP"PWR_MLCC_CAP"
BOM_SS"E15431-004"
CDS_LIB"dev_discrete"
SEC"1"
SEC_TYPE"0603V"
CDS_SEC"1"
CDS_LOCATION"C5A7";
"B"
$PN"2"12;
"A"
$PN"1"11;
%"CAP_A"
"1","(200,100)","0","dev_discrete","I270";
;
VALUE"47UF"
PART_NUMBER"602433-106"
MATERIAL"X5R"
TOLERANCE"20%"
VOLTAGE"4V"
LOCATION"C5A3"
PACK_TYPE"0603V"
GROUP"PWR_MLCC_CAP"
BOM_SS"E15431-004"
CDS_LIB"dev_discrete"
SEC"1"
SEC_TYPE"0603V"
CDS_SEC"1"
CDS_LOCATION"C5A3";
"B"
$PN"2"12;
"A"
$PN"1"11;
%"CAP_A"
"1","(500,100)","0","dev_discrete","I271";
;
VALUE"47UF"
PACK_TYPE"0603V"
PART_NUMBER"602433-106"
VOLTAGE"4V"
MATERIAL"X5R"
TOLERANCE"20%"
LOCATION"C5A8"
GROUP"PWR_MLCC_CAP"
BOM_SS"E15431-004"
CDS_SEC"1"
SEC_TYPE"0603V"
SEC"1"
CDS_LIB"dev_discrete"
CDS_LOCATION"C5A8";
"B"
$PN"2"12;
"A"
$PN"1"11;
%"CAP_A"
"1","(800,100)","0","dev_discrete","I272";
;
VALUE"47UF"
LOCATION"C5A9"
PART_NUMBER"602433-106"
PACK_TYPE"0603V"
TOLERANCE"20%"
MATERIAL"X5R"
VOLTAGE"4V"
GROUP"PWR_MLCC_CAP"
BOM_SS"E15431-004"
CDS_LIB"dev_discrete"
SEC"1"
SEC_TYPE"0603V"
CDS_SEC"1"
CDS_LOCATION"C5A9";
"B"
$PN"2"12;
"A"
$PN"1"11;
%"CAP_A"
"1","(1075,100)","0","dev_discrete","I273";
;
PACK_TYPE"0603V"
PART_NUMBER"602433-106"
LOCATION"C5A16"
TOLERANCE"20%"
MATERIAL"X5R"
VALUE"47UF"
VOLTAGE"4V"
GROUP"PWR_MLCC_CAP"
BOM_SS"E15431-004"
CDS_LIB"dev_discrete"
SEC"1"
SEC_TYPE"0603V"
CDS_SEC"1"
CDS_LOCATION"C5A16";
"B"
$PN"2"12;
"A"
$PN"1"11;
%"CAP_A"
"1","(1350,100)","0","dev_discrete","I274";
;
GROUP"PWR_MLCC_CAP"
VOLTAGE"4V"
VALUE"47UF"
TOLERANCE"20%"
LOCATION"C5A4"
PART_NUMBER"602433-106"
MATERIAL"X5R"
PACK_TYPE"0603V"
BOM_SS"E15431-004"
CDS_SEC"1"
SEC_TYPE"0603V"
SEC"1"
CDS_LIB"dev_discrete"
CDS_LOCATION"C5A4";
"B"
$PN"2"12;
"A"
$PN"1"11;
%"CAP_A"
"1","(1650,100)","0","dev_discrete","I275";
;
GROUP"PWR_MLCC_CAP"
PACK_TYPE"0603V"
PART_NUMBER"602433-106"
MATERIAL"X5R"
TOLERANCE"20%"
VOLTAGE"4V"
VALUE"47UF"
LOCATION"C5A17"
BOM_SS"E15431-004"
CDS_LIB"dev_discrete"
SEC"1"
SEC_TYPE"0603V"
CDS_SEC"1"
CDS_LOCATION"C5A17";
"B"
$PN"2"12;
"A"
$PN"1"11;
%"CAP_A"
"1","(1950,100)","0","dev_discrete","I276";
;
GROUP"PWR_MLCC_CAP"
PART_NUMBER"602433-106"
LOCATION"C5A18"
VOLTAGE"4V"
VALUE"47UF"
MATERIAL"X5R"
TOLERANCE"20%"
PACK_TYPE"0603V"
BOM_SS"E15431-004"
CDS_SEC"1"
SEC_TYPE"0603V"
SEC"1"
CDS_LIB"dev_discrete"
CDS_LOCATION"C5A18";
"B"
$PN"2"12;
"A"
$PN"1"11;
%"CAP_A"
"1","(2225,100)","0","dev_discrete","I277";
;
PART_NUMBER"602433-106"
LOCATION"C5A19"
VALUE"47UF"
VOLTAGE"4V"
MATERIAL"X5R"
TOLERANCE"20%"
PACK_TYPE"0603V"
GROUP"PWR_MLCC_CAP"
BOM_SS"E15431-004"
CDS_SEC"1"
SEC_TYPE"0603V"
SEC"1"
CDS_LIB"dev_discrete"
CDS_LOCATION"C5A19";
"B"
$PN"2"12;
"A"
$PN"1"11;
%"CAP_A"
"1","(-2150,-650)","0","dev_discrete","I278";
;
GROUP"PWR_MLCC_CAP"
VALUE"47UF"
LOCATION"C5L6"
TOLERANCE"20%"
MATERIAL"X5R"
PACK_TYPE"0603V"
PART_NUMBER"602433-106"
VOLTAGE"4V"
BOM_SS"E15431-004"
CDS_LIB"dev_discrete"
SEC"1"
SEC_TYPE"0603V"
CDS_SEC"1"
CDS_LOCATION"C5L6";
"B"
$PN"2"14;
"A"
$PN"1"13;
%"CAP_A"
"1","(-1850,-650)","0","dev_discrete","I279";
;
GROUP"PWR_MLCC_CAP"
LOCATION"C5L7"
TOLERANCE"20%"
PACK_TYPE"0603V"
MATERIAL"X5R"
PART_NUMBER"602433-106"
VOLTAGE"4V"
VALUE"47UF"
BOM_SS"E15431-004"
CDS_SEC"1"
SEC_TYPE"0603V"
SEC"1"
CDS_LIB"dev_discrete"
CDS_LOCATION"C5L7";
"B"
$PN"2"14;
"A"
$PN"1"13;
%"CAP_A"
"1","(-1550,-650)","0","dev_discrete","I280";
;
GROUP"PWR_MLCC_CAP"
PART_NUMBER"602433-106"
PACK_TYPE"0603V"
TOLERANCE"20%"
MATERIAL"X5R"
VOLTAGE"4V"
LOCATION"C5L8"
VALUE"47UF"
BOM_SS"E15431-004"
CDS_LIB"dev_discrete"
SEC"1"
SEC_TYPE"0603V"
CDS_SEC"1"
CDS_LOCATION"C5L8";
"B"
$PN"2"14;
"A"
$PN"1"13;
%"CAP_A"
"1","(-1275,-650)","0","dev_discrete","I281";
;
GROUP"PWR_MLCC_CAP"
LOCATION"C5L9"
MATERIAL"X5R"
TOLERANCE"20%"
VOLTAGE"4V"
VALUE"47UF"
PACK_TYPE"0603V"
PART_NUMBER"602433-106"
BOM_SS"E15431-004"
CDS_SEC"1"
SEC_TYPE"0603V"
SEC"1"
CDS_LIB"dev_discrete"
CDS_LOCATION"C5L9";
"B"
$PN"2"14;
"A"
$PN"1"13;
%"CAP_A"
"1","(-1000,-650)","0","dev_discrete","I282";
;
GROUP"PWR_MLCC_CAP"
MATERIAL"X5R"
PART_NUMBER"602433-106"
PACK_TYPE"0603V"
LOCATION"C5L10"
TOLERANCE"20%"
VALUE"47UF"
VOLTAGE"4V"
BOM_SS"E15431-004"
CDS_LIB"dev_discrete"
SEC"1"
SEC_TYPE"0603V"
CDS_SEC"1"
CDS_LOCATION"C5L10";
"B"
$PN"2"14;
"A"
$PN"1"13;
%"CAP_A"
"1","(-700,-650)","0","dev_discrete","I283";
;
GROUP"PWR_MLCC_CAP"
VALUE"47UF"
PART_NUMBER"602433-106"
PACK_TYPE"0603V"
LOCATION"C5L11"
VOLTAGE"4V"
MATERIAL"X5R"
TOLERANCE"20%"
BOM_SS"E15431-004"
CDS_SEC"1"
SEC_TYPE"0603V"
SEC"1"
CDS_LIB"dev_discrete"
CDS_LOCATION"C5L11";
"B"
$PN"2"14;
"A"
$PN"1"13;
%"CAP_A"
"1","(-400,-650)","0","dev_discrete","I284";
;
GROUP"PWR_MLCC_CAP"
TOLERANCE"20%"
LOCATION"C5L12"
VALUE"47UF"
PACK_TYPE"0603V"
PART_NUMBER"602433-106"
VOLTAGE"4V"
MATERIAL"X5R"
BOM_SS"E15431-004"
CDS_LIB"dev_discrete"
SEC"1"
SEC_TYPE"0603V"
CDS_SEC"1"
CDS_LOCATION"C5L12";
"B"
$PN"2"14;
"A"
$PN"1"13;
%"CAP_A"
"1","(-125,-650)","0","dev_discrete","I285";
;
GROUP"PWR_MLCC_CAP"
MATERIAL"X5R"
PART_NUMBER"602433-106"
LOCATION"C5L13"
VALUE"47UF"
TOLERANCE"20%"
VOLTAGE"4V"
PACK_TYPE"0603V"
BOM_SS"E15431-004"
CDS_SEC"1"
SEC_TYPE"0603V"
SEC"1"
CDS_LIB"dev_discrete"
CDS_LOCATION"C5L13";
"B"
$PN"2"14;
"A"
$PN"1"13;
%"CAP_A"
"1","(200,-650)","0","dev_discrete","I286";
;
PART_NUMBER"602433-106"
GROUP"PWR_MLCC_CAP"
MATERIAL"X5R"
TOLERANCE"20%"
PACK_TYPE"0603V"
VALUE"47UF"
LOCATION"C5M7"
VOLTAGE"4V"
BOM_SS"E15431-004"
CDS_LIB"dev_discrete"
SEC"1"
SEC_TYPE"0603V"
CDS_SEC"1"
CDS_LOCATION"C5M7";
"B"
$PN"2"14;
"A"
$PN"1"13;
%"CAP_A"
"1","(500,-650)","0","dev_discrete","I287";
;
GROUP"PWR_MLCC_CAP"
TOLERANCE"20%"
MATERIAL"X5R"
PART_NUMBER"602433-106"
LOCATION"C5M6"
VOLTAGE"4V"
VALUE"47UF"
PACK_TYPE"0603V"
BOM_SS"E15431-004"
CDS_SEC"1"
SEC_TYPE"0603V"
SEC"1"
CDS_LIB"dev_discrete"
CDS_LOCATION"C5M6";
"B"
$PN"2"14;
"A"
$PN"1"13;
%"CAP_A"
"1","(800,-650)","0","dev_discrete","I288";
;
GROUP"PWR_MLCC_CAP"
LOCATION"C5M5"
VALUE"47UF"
TOLERANCE"20%"
PART_NUMBER"602433-106"
MATERIAL"X5R"
VOLTAGE"4V"
PACK_TYPE"0603V"
BOM_SS"E15431-004"
CDS_LIB"dev_discrete"
SEC"1"
SEC_TYPE"0603V"
CDS_SEC"1"
CDS_LOCATION"C5M5";
"B"
$PN"2"14;
"A"
$PN"1"13;
%"CAP_A"
"1","(1075,-650)","0","dev_discrete","I289";
;
GROUP"PWR_MLCC_CAP"
PART_NUMBER"602433-106"
TOLERANCE"20%"
PACK_TYPE"0603V"
LOCATION"C5M4"
VOLTAGE"4V"
VALUE"47UF"
MATERIAL"X5R"
BOM_SS"E15431-004"
CDS_SEC"1"
SEC_TYPE"0603V"
SEC"1"
CDS_LIB"dev_discrete"
CDS_LOCATION"C5M4";
"B"
$PN"2"14;
"A"
$PN"1"13;
%"CAP_A"
"1","(1350,-650)","0","dev_discrete","I290";
;
GROUP"PWR_MLCC_CAP"
PART_NUMBER"602433-106"
PACK_TYPE"0603V"
TOLERANCE"20%"
MATERIAL"X5R"
VALUE"47UF"
VOLTAGE"4V"
LOCATION"C5M2"
BOM_SS"E15431-004"
CDS_LIB"dev_discrete"
SEC"1"
SEC_TYPE"0603V"
CDS_SEC"1"
CDS_LOCATION"C5M2";
"B"
$PN"2"14;
"A"
$PN"1"13;
%"CAP_A"
"1","(1650,-650)","0","dev_discrete","I291";
;
PACK_TYPE"0603V"
GROUP"PWR_MLCC_CAP"
MATERIAL"X5R"
LOCATION"C5M1"
VOLTAGE"4V"
TOLERANCE"20%"
VALUE"47UF"
PART_NUMBER"602433-106"
BOM_SS"E15431-004"
CDS_SEC"1"
SEC_TYPE"0603V"
SEC"1"
CDS_LIB"dev_discrete"
CDS_LOCATION"C5M1";
"B"
$PN"2"14;
"A"
$PN"1"13;
%"CAP_A"
"1","(1950,-650)","0","dev_discrete","I292";
;
PART_NUMBER"602433-106"
GROUP"PWR_MLCC_CAP"
TOLERANCE"20%"
LOCATION"C4M2"
VALUE"47UF"
PACK_TYPE"0603V"
MATERIAL"X5R"
VOLTAGE"4V"
BOM_SS"E15431-004"
CDS_LIB"dev_discrete"
SEC"1"
SEC_TYPE"0603V"
CDS_SEC"1"
CDS_LOCATION"C4M2";
"B"
$PN"2"14;
"A"
$PN"1"13;
%"CAP_A"
"1","(2225,-650)","0","dev_discrete","I293";
;
MATERIAL"X5R"
PART_NUMBER"602433-106"
TOLERANCE"20%"
GROUP"PWR_MLCC_CAP"
VOLTAGE"4V"
LOCATION"C5A11"
PACK_TYPE"0603V"
VALUE"47UF"
BOM_SS"E15431-004"
CDS_LIB"dev_discrete"
SEC"1"
SEC_TYPE"0603V"
CDS_SEC"1"
CDS_LOCATION"C5A11";
"B"
$PN"2"14;
"A"
$PN"1"13;
%"SC22U16V5MX-4-GP"
"1","(-500,1025)","0","w_hdl","I298";
;
VALUE"SC22U16V5MX-4-GP"
TYPE"X6S"
PACK_SIZE"0805"
ATTRIBUTE"22UF"
TOLERANCE"20%"
LOCATION"C7W5"
RATED"16V"
CDS_LOCATION"C7W5"
CDS_LMAN_SYM_OUTLINE"-50,25,50,-25"
CDS_LIB"w_hdl"
PART_NUMBER"078.22611.0811"
SEC_TYPE"SMD-BCG5"
SEC"1"
PACK_TYPE"SMD-BCG5"
CDS_SEC"1";
"2"
$PN"2"21;
"1"
$PN"1"3;
%"SC22U16V5MX-4-GP"
"1","(700,1025)","0","w_hdl","I299";
;
TYPE"X6S"
VALUE"SC22U16V5MX-4-GP"
PACK_SIZE"0805"
RATED"16V"
TOLERANCE"20%"
ATTRIBUTE"22UF"
LOCATION"C7W9"
CDS_LOCATION"C7W9"
CDS_LMAN_SYM_OUTLINE"-50,25,50,-25"
CDS_LIB"w_hdl"
PART_NUMBER"078.22611.0811"
SEC_TYPE"SMD-BCG5"
SEC"1"
PACK_TYPE"SMD-BCG5"
CDS_SEC"1";
"2"
$PN"2"21;
"1"
$PN"1"3;
%"SC22U16V5MX-4-GP"
"1","(400,1025)","0","w_hdl","I300";
;
PACK_SIZE"0805"
TYPE"X6S"
RATED"16V"
ATTRIBUTE"22UF"
LOCATION"C7W8"
TOLERANCE"20%"
VALUE"SC22U16V5MX-4-GP"
CDS_LOCATION"C7W8"
CDS_LMAN_SYM_OUTLINE"-50,25,50,-25"
CDS_LIB"w_hdl"
PART_NUMBER"078.22611.0811"
SEC_TYPE"SMD-BCG5"
SEC"1"
PACK_TYPE"SMD-BCG5"
CDS_SEC"1";
"2"
$PN"2"21;
"1"
$PN"1"3;
%"SC22U16V5MX-4-GP"
"1","(100,1025)","0","w_hdl","I301";
;
VALUE"SC22U16V5MX-4-GP"
PACK_SIZE"0805"
RATED"16V"
ATTRIBUTE"22UF"
LOCATION"C7W7"
TOLERANCE"20%"
TYPE"X6S"
CDS_SEC"1"
PACK_TYPE"SMD-BCG5"
SEC"1"
SEC_TYPE"SMD-BCG5"
PART_NUMBER"078.22611.0811"
CDS_LIB"w_hdl"
CDS_LMAN_SYM_OUTLINE"-50,25,50,-25"
CDS_LOCATION"C7W7";
"2"
$PN"2"21;
"1"
$PN"1"3;
%"SC22U16V5MX-4-GP"
"1","(-200,1025)","0","w_hdl","I302";
;
VALUE"SC22U16V5MX-4-GP"
TYPE"X6S"
LOCATION"C7W6"
ATTRIBUTE"22UF"
TOLERANCE"20%"
PACK_SIZE"0805"
RATED"16V"
CDS_LOCATION"C7W6"
CDS_LMAN_SYM_OUTLINE"-50,25,50,-25"
CDS_LIB"w_hdl"
PART_NUMBER"078.22611.0811"
SEC_TYPE"SMD-BCG5"
SEC"1"
PACK_TYPE"SMD-BCG5"
CDS_SEC"1";
"2"
$PN"2"21;
"1"
$PN"1"3;
%"SC22U16V5MX-4-GP"
"1","(1900,1025)","0","w_hdl","I303";
;
RATED"16V"
VALUE"SC22U16V5MX-4-GP"
TOLERANCE"20%"
TYPE"X6S"
PACK_SIZE"0805"
LOCATION"C7W13"
ATTRIBUTE"22UF"
CDS_LOCATION"C7W13"
CDS_LMAN_SYM_OUTLINE"-50,25,50,-25"
CDS_LIB"w_hdl"
PART_NUMBER"078.22611.0811"
SEC_TYPE"SMD-BCG5"
SEC"1"
PACK_TYPE"SMD-BCG5"
CDS_SEC"1";
"2"
$PN"2"21;
"1"
$PN"1"3;
%"SC22U16V5MX-4-GP"
"1","(1600,1025)","0","w_hdl","I304";
;
RATED"16V"
VALUE"SC22U16V5MX-4-GP"
TOLERANCE"20%"
PACK_SIZE"0805"
LOCATION"C7W12"
ATTRIBUTE"22UF"
TYPE"X6S"
CDS_SEC"1"
PACK_TYPE"SMD-BCG5"
SEC"1"
SEC_TYPE"SMD-BCG5"
PART_NUMBER"078.22611.0811"
CDS_LIB"w_hdl"
CDS_LMAN_SYM_OUTLINE"-50,25,50,-25"
CDS_LOCATION"C7W12";
"2"
$PN"2"21;
"1"
$PN"1"3;
%"SC22U16V5MX-4-GP"
"1","(1300,1025)","0","w_hdl","I305";
;
RATED"16V"
VALUE"SC22U16V5MX-4-GP"
ATTRIBUTE"22UF"
LOCATION"C7W11"
TYPE"X6S"
PACK_SIZE"0805"
TOLERANCE"20%"
CDS_SEC"1"
PACK_TYPE"SMD-BCG5"
SEC"1"
SEC_TYPE"SMD-BCG5"
PART_NUMBER"078.22611.0811"
CDS_LIB"w_hdl"
CDS_LMAN_SYM_OUTLINE"-50,25,50,-25"
CDS_LOCATION"C7W11";
"2"
$PN"2"21;
"1"
$PN"1"3;
%"SC22U16V5MX-4-GP"
"1","(1000,1025)","0","w_hdl","I306";
;
VALUE"SC22U16V5MX-4-GP"
RATED"16V"
LOCATION"C7W10"
ATTRIBUTE"22UF"
TOLERANCE"20%"
TYPE"X6S"
PACK_SIZE"0805"
CDS_LOCATION"C7W10"
CDS_LMAN_SYM_OUTLINE"-50,25,50,-25"
CDS_LIB"w_hdl"
PART_NUMBER"078.22611.0811"
SEC_TYPE"SMD-BCG5"
SEC"1"
PACK_TYPE"SMD-BCG5"
CDS_SEC"1";
"2"
$PN"2"21;
"1"
$PN"1"3;
%"GND"
"1","(1900,725)","0","mstr_symbols","I307";
;
HDL_POWER"GND"
BODY_TYPE"PLUMBING"
SIZE"1B"
VOLTAGE"0"
CDS_LIB"mstr_symbols"
BOM_COST"MEM_VRD_PVDDQ_DEF"
ROOM"VDDQ_DEF_PWR_VR";
"A\NAC"21;
%"CAP"
"1","(2750,2825)","0","mstr_discrete","I308";
;
NEW_PN"078.1071T.M002"
TOLERANCE"20%"
VOLTAGE"4V"
NEW_MATERIAL"X6S"
PART_NUMBER"602433-112"
VALUE"100UF"
BOM_SS"NOPOP"
LOCATION"C5A20"
GROUP"PWR_MLCC_CAP"
PACK_TYPE"0805"
CDS_SEC"1"
CDS_LIB"mstr_discrete"
BOM_COST"MEM_VRD_PVDDQ_CD"
ROOM"VDDQ_ABC_PWR_VR"
SEC_TYPE"0805"
SEC"1"
MATERIAL"X5R"
CDS_LOCATION"C5A20";
"A"
$PN"1"26;
"B"
$PN"2"27;
%"CAP"
"1","(3150,2825)","0","mstr_discrete","I309";
;
NEW_PN"078.1071T.M002"
LOCATION"C5L1"
VOLTAGE"4V"
TOLERANCE"20%"
PACK_TYPE"0805"
VALUE"100UF"
PART_NUMBER"602433-112"
NEW_MATERIAL"X6S"
BOM_SS"NOPOP"
GROUP"PWR_MLCC_CAP"
MATERIAL"X5R"
SEC"1"
SEC_TYPE"0805"
ROOM"VDDQ_ABC_PWR_VR"
BOM_COST"MEM_VRD_PVDDQ_CD"
CDS_LIB"mstr_discrete"
CDS_SEC"1"
CDS_LOCATION"C5L1";
"A"
$PN"1"26;
"B"
$PN"2"27;
%"CAP"
"1","(3850,2825)","0","mstr_discrete","I310";
;
NEW_PN"078.1071T.M002"
LOCATION"C5L3"
VOLTAGE"4V"
VALUE"100UF"
TOLERANCE"20%"
PART_NUMBER"602433-112"
PACK_TYPE"0805"
NEW_MATERIAL"X6S"
BOM_SS"NOPOP"
GROUP"PWR_MLCC_CAP"
MATERIAL"X5R"
SEC"1"
SEC_TYPE"0805"
ROOM"VDDQ_ABC_PWR_VR"
BOM_COST"MEM_VRD_PVDDQ_CD"
CDS_LIB"mstr_discrete"
CDS_SEC"1"
CDS_LOCATION"C5L3";
"A"
$PN"1"26;
"B"
$PN"2"27;
%"CAP"
"1","(3500,2825)","0","mstr_discrete","I311";
;
CDS_SEC"1"
$SEC"1"
CDS_LOCATION"C5L2"
NEW_PN"078.1071T.M002"
PART_NUMBER"602433-112"
TOLERANCE"20%"
VALUE"100UF"
VOLTAGE"4V"
PACK_TYPE"0805"
NEW_MATERIAL"X6S"
GROUP"PWR_MLCC_CAP"
BOM_SS"NOPOP"
LOCATION"C5L2"
CDS_LIB"mstr_discrete"
BOM_COST"MEM_VRD_PVDDQ_CD"
ROOM"VDDQ_ABC_PWR_VR"
MATERIAL"X5R";
"A"
$PN"1"26;
"B"
$PN"2"27;
%"CAP"
"1","(4250,2825)","0","mstr_discrete","I312";
;
NEW_PN"078.1071T.M002"
PACK_TYPE"0805"
PART_NUMBER"602433-112"
LOCATION"C5M12"
VALUE"100UF"
TOLERANCE"20%"
VOLTAGE"4V"
NEW_MATERIAL"X6S"
BOM_SS"NOPOP"
GROUP"PWR_MLCC_CAP"
CDS_SEC"1"
CDS_LIB"mstr_discrete"
BOM_COST"MEM_VRD_PVDDQ_CD"
ROOM"VDDQ_ABC_PWR_VR"
SEC_TYPE"0805"
SEC"1"
MATERIAL"X5R"
CDS_LOCATION"C5M12";
"A"
$PN"1"26;
"B"
$PN"2"27;
%"CAP"
"1","(4600,2825)","0","mstr_discrete","I313";
;
NEW_PN"078.1071T.M002"
PART_NUMBER"602433-112"
VALUE"100UF"
LOCATION"C5L14"
PACK_TYPE"0805"
VOLTAGE"4V"
TOLERANCE"20%"
NEW_MATERIAL"X6S"
BOM_SS"NOPOP"
GROUP"PWR_MLCC_CAP"
MATERIAL"X5R"
SEC"1"
SEC_TYPE"0805"
ROOM"VDDQ_ABC_PWR_VR"
BOM_COST"MEM_VRD_PVDDQ_CD"
CDS_LIB"mstr_discrete"
CDS_SEC"1"
CDS_LOCATION"C5L14";
"A"
$PN"1"26;
"B"
$PN"2"27;
%"CAP"
"1","(5000,2825)","0","mstr_discrete","I314";
;
NEW_PN"078.1071T.M002"
PACK_TYPE"0805"
LOCATION"C5M8"
VOLTAGE"4V"
PART_NUMBER"602433-112"
BOM_SS"NOPOP"
GROUP"PWR_MLCC_CAP"
NEW_MATERIAL"X6S"
VALUE"100UF"
TOLERANCE"20%"
CDS_SEC"1"
CDS_LIB"mstr_discrete"
BOM_COST"MEM_VRD_PVDDQ_CD"
ROOM"VDDQ_ABC_PWR_VR"
SEC_TYPE"0805"
SEC"1"
MATERIAL"X5R"
CDS_LOCATION"C5M8";
"A"
$PN"1"26;
"B"
$PN"2"27;
%"CAP"
"1","(1600,2950)","0","mstr_discrete","I315";
;
LOCATION"C5P3"
PART_NUMBER"602433-112"
NEW_MATERIAL"X6S"
BOM_SS"NOPOP"
TOLERANCE"20%"
PACK_TYPE"0805"
VALUE"100UF"
VOLTAGE"4V"
GROUP"PWR_MLCC_CAP"
NEW_PN"078.1071T.M002"
CDS_SEC"1"
CDS_LIB"mstr_discrete"
BOM_COST"MEM_VRD_PVDDQ_CD"
ROOM"VDDQ_ABC_PWR_VR"
SEC_TYPE"0805"
SEC"1"
MATERIAL"X5R"
CDS_LOCATION"C5P3";
"A"
$PN"1"20;
"B"
$PN"2"19;
%"CAP"
"1","(175,2925)","0","mstr_discrete","I316";
;
NEW_PN"078.1071T.M002"
VALUE"100UF"
LOCATION"C5P6"
PACK_TYPE"0805"
PART_NUMBER"602433-112"
TOLERANCE"20%"
VOLTAGE"4V"
NEW_MATERIAL"X6S"
BOM_SS"NOPOP"
GROUP"PWR_MLCC_CAP"
MATERIAL"X5R"
SEC"1"
SEC_TYPE"0805"
ROOM"VDDQ_ABC_PWR_VR"
BOM_COST"MEM_VRD_PVDDQ_CD"
CDS_LIB"mstr_discrete"
CDS_SEC"1"
CDS_LOCATION"C5P6";
"A"
$PN"1"16;
"B"
$PN"2"15;
%"CAP"
"1","(500,2925)","0","mstr_discrete","I317";
;
VALUE"100UF"
VOLTAGE"4V"
TOLERANCE"20%"
PART_NUMBER"602433-112"
BOM_SS"NOPOP"
PACK_TYPE"0805"
LOCATION"C5P5"
GROUP"PWR_MLCC_CAP"
NEW_MATERIAL"X6S"
NEW_PN"078.1071T.M002"
MATERIAL"X5R"
SEC"1"
SEC_TYPE"0805"
ROOM"VDDQ_ABC_PWR_VR"
BOM_COST"MEM_VRD_PVDDQ_CD"
CDS_LIB"mstr_discrete"
CDS_SEC"1"
CDS_LOCATION"C5P5";
"A"
$PN"1"16;
"B"
$PN"2"15;
%"CAP"
"1","(800,2925)","0","mstr_discrete","I318";
;
VALUE"100UF"
TOLERANCE"20%"
PACK_TYPE"0805"
LOCATION"C5P4"
VOLTAGE"4V"
GROUP"PWR_MLCC_CAP"
NEW_MATERIAL"X6S"
PART_NUMBER"602433-112"
BOM_SS"NOPOP"
NEW_PN"078.1071T.M002"
MATERIAL"X5R"
SEC"1"
SEC_TYPE"0805"
ROOM"VDDQ_ABC_PWR_VR"
BOM_COST"MEM_VRD_PVDDQ_CD"
CDS_LIB"mstr_discrete"
CDS_SEC"1"
CDS_LOCATION"C5P4";
"A"
$PN"1"16;
"B"
$PN"2"15;
%"CAP"
"1","(-2300,2975)","0","mstr_discrete","I319";
;
NEW_PN"078.1071T.M002"
NEW_MATERIAL"X6S"
GROUP"PWR_MLCC_CAP"
BOM_SS"NOPOP"
TOLERANCE"20%"
VOLTAGE"4V"
VALUE"100UF"
PART_NUMBER"602433-112"
PACK_TYPE"0805"
LOCATION"C5P2"
CDS_SEC"1"
CDS_LIB"mstr_discrete"
BOM_COST"MEM_VRD_PVDDQ_CD"
ROOM"VDDQ_ABC_PWR_VR"
SEC_TYPE"0805"
SEC"1"
MATERIAL"X5R"
CDS_LOCATION"C5P2";
"A"
$PN"1"6;
"B"
$PN"2"10;
%"CAP"
"1","(-1950,2975)","0","mstr_discrete","I320";
;
NEW_PN"078.1071T.M002"
LOCATION"C5P1"
GROUP"PWR_MLCC_CAP"
NEW_MATERIAL"X6S"
BOM_SS"NOPOP"
VALUE"100UF"
PART_NUMBER"602433-112"
VOLTAGE"4V"
TOLERANCE"20%"
PACK_TYPE"0805"
CDS_SEC"1"
CDS_LIB"mstr_discrete"
BOM_COST"MEM_VRD_PVDDQ_CD"
ROOM"VDDQ_ABC_PWR_VR"
SEC_TYPE"0805"
SEC"1"
MATERIAL"X5R"
CDS_LOCATION"C5P1";
"A"
$PN"1"6;
"B"
$PN"2"10;
%"CAP"
"1","(2400,2825)","0","mstr_discrete","I321";
;
NEW_PN"078.1071T.M002"
VOLTAGE"4V"
PACK_TYPE"0805"
TOLERANCE"20%"
NEW_MATERIAL"X6S"
BOM_SS"NOPOP"
GROUP"PWR_MLCC_CAP"
PART_NUMBER"602433-112"
VALUE"100UF"
LOCATION"C5A10"
MATERIAL"X5R"
SEC"1"
SEC_TYPE"0805"
ROOM"VDDQ_ABC_PWR_VR"
BOM_COST"MEM_VRD_PVDDQ_CD"
CDS_LIB"mstr_discrete"
CDS_SEC"1"
CDS_LOCATION"C5A10";
"A"
$PN"1"26;
"B"
$PN"2"27;
%"SE100U16VM-48-GP"
"1","(-1450,1025)","0","w_hdl","I324";
;
CDS_SEC"1"
CDS_LOCATION"C7W2"
RATED"16V"
ATTRIBUTE"100UF"
VALUE"SE100U16VM-48-GP"
LOCATION"C7W2"
PACK_TYPE"SMD-TCG2"
SEC"1"
SEC_TYPE"SMD-TCG2"
PART_NUMBER"077.51081.0011"
CDS_LIB"w_hdl"
CDS_LMAN_SYM_OUTLINE"-50,25,50,-25";
"2"
$PN"2"21;
"1"
$PN"1"3;
%"RES"
"2","(4100,-100)","0","mstr_discrete","I58";
;
WATTAGE"1/10W"
PART_NUMBER"G22026-003"
PACK_TYPE"0603"
MATERIAL"CHIP"
TOLERANCE"1%"
LOCATION"R4L4"
VALUE"120.0"
CDS_LIB"mstr_discrete"
CDS_LOCATION"R4L4"
BOM_COST"MEM_VRD_PVPP_DEF"
ROOM"VDDQ_DEF_PWR_VR"
$SEC"1"
CDS_SEC"1";
"A"
$PN"1"24;
"B"
$PN"2"25;
%"GND"
"1","(-50,1550)","0","mstr_symbols","I65";
;
HDL_POWER"GND"
BODY_TYPE"PLUMBING"
ROOM"VDDQ_DEF_PWR_VR"
BOM_COST"MEM_VRD_PVPP_DEF"
CDS_LIB"mstr_symbols"
VOLTAGE"0"
SIZE"1B";
"A\NAC"22;
%"PVDDQ_DEF"
"1","(-25,2275)","0","mstr_symbols","I73";
;
ROOM"VDDQ_DEF_PWR_VR"
BOM_COST"MEM_VRD_PVPP_DEF"
CDS_LIB"mstr_symbols"
VOLTAGE"1.2V"
BODY_TYPE"PLUMBING"
HDL_POWER"PVDDQ_DEF";
"G\NAC"23;
%"RES"
"2","(-700,1825)","0","mstr_discrete","I74";
;
CDS_SEC"1"
MATERIAL"EMPTY"
VALUE"100.0"
WATTAGE"1/16W"
PART_NUMBER"G21796-017"
PACK_TYPE"0402"
TOLERANCE"1%"
LOCATION"R4L2"
SEC"1"
SEC_TYPE"0402"
ROOM"VDDQ_DEF_PWR_VR"
CDS_LOCATION"R4L2"
CDS_LIB"mstr_discrete";
"A"
$PN"1"28;
"B"
$PN"2"29;
%"CAPP"
"1","(2900,-100)","0","mstr_discrete","I75";
;
CDS_SEC"1"
GROUP"PWR_BULK_CAP"
PACK_TYPE"3018"
MATERIAL"ALUM"
VOLTAGE"2.5V"
TOLERANCE"20%"
VALUE"470UF"
LOCATION"C3L6"
PART_NUMBER"699013-049"
SEC"1"
SEC_TYPE"3018"
ROOM"VDDQ_DEF_PWR_VR"
CDS_LOCATION"C3L6"
CDS_LIB"mstr_discrete";
"B"
$PN"2"25;
"A"
$PN"1"24;
%"CAPP"
"1","(3200,-100)","0","mstr_discrete","I76";
;
CDS_SEC"1"
GROUP"PWR_BULK_CAP"
LOCATION"C3L14"
VALUE"470UF"
TOLERANCE"20%"
VOLTAGE"2.5V"
MATERIAL"ALUM"
PART_NUMBER"699013-049"
PACK_TYPE"3018"
CDS_LIB"mstr_discrete"
CDS_LOCATION"C3L14"
ROOM"VDDQ_DEF_PWR_VR"
SEC_TYPE"3018"
SEC"1";
"B"
$PN"2"25;
"A"
$PN"1"24;
%"CAPP"
"1","(3500,-100)","0","mstr_discrete","I77";
;
CDS_SEC"1"
GROUP"PWR_BULK_CAP"
LOCATION"C6A5"
VALUE"470UF"
TOLERANCE"20%"
MATERIAL"ALUM"
PART_NUMBER"699013-049"
PACK_TYPE"3018"
VOLTAGE"2.5V"
SEC"1"
SEC_TYPE"3018"
ROOM"VDDQ_DEF_PWR_VR"
CDS_LOCATION"C6A5"
CDS_LIB"mstr_discrete";
"B"
$PN"2"25;
"A"
$PN"1"24;
%"CAPP"
"1","(3800,-100)","0","mstr_discrete","I78";
;
CDS_SEC"1"
GROUP"PWR_BULK_CAP"
PART_NUMBER"699013-049"
LOCATION"C4L5"
PACK_TYPE"3018"
MATERIAL"ALUM"
VOLTAGE"2.5V"
TOLERANCE"20%"
VALUE"470UF"
SEC_TYPE"3018"
SEC"1"
ROOM"VDDQ_DEF_PWR_VR"
CDS_LOCATION"C4L5"
CDS_LIB"mstr_discrete";
"B"
$PN"2"25;
"A"
$PN"1"24;
%"PVDDQ_DEF"
"1","(2900,200)","0","mstr_symbols","I80";
;
ROOM"VDDQ_DEF_PWR_VR"
BOM_COST"MEM_VRD_PVPP_DEF"
CDS_LIB"mstr_symbols"
VOLTAGE"1.2V"
BODY_TYPE"PLUMBING"
HDL_POWER"PVDDQ_DEF";
"G\NAC"24;
%"GND"
"1","(2900,-575)","0","mstr_symbols","I81";
;
HDL_POWER"GND"
BODY_TYPE"PLUMBING"
CDS_LIB"mstr_symbols"
SIZE"1B"
VOLTAGE"0";
"A\NAC"25;
%"PVDDQ_DEF"
"1","(2400,3100)","0","mstr_symbols","I93";
;
ROOM"VDDQ_DEF_PWR_VR"
BOM_COST"MEM_VRD_PVDDQ_DEF"
CDS_LIB"mstr_symbols"
VOLTAGE"1.2V"
BODY_TYPE"PLUMBING"
HDL_POWER"PVDDQ_DEF";
"G\NAC"26;
%"GND"
"1","(2400,2350)","0","mstr_symbols","I94";
;
VOLTAGE"0"
SIZE"1B"
CDS_LIB"mstr_symbols"
BOM_COST"MEM_VRD_PVDDQ_DEF"
ROOM"VDDQ_DEF_PWR_VR"
BODY_TYPE"PLUMBING"
HDL_POWER"GND";
"A\NAC"27;
END.
